(kicad_pcb
	(version 20260206)
	(generator "pcbnew")
	(generator_version "10.0")
	(general
		(thickness 1.6)
		(legacy_teardrops no)
	)
	(paper "A4")
	(title_block
		(title "timecard-production-celestica-r4006 — R4006-B0001-02_R01.brd")
		(comment 1 "Time Appliance Project (Time Card) / footprints 598-600 of 1113")
	)
	(layers
		(0 "F.Cu" signal "TOP")
		(4 "In1.Cu" signal "L02_GND1")
		(6 "In2.Cu" signal "L03_SIG1")
		(8 "In3.Cu" signal "L04_GND2")
		(10 "In4.Cu" signal "L05_VCC1")
		(12 "In5.Cu" signal "L06_VCC2")
		(14 "In6.Cu" signal "L07_GND3")
		(16 "In7.Cu" signal "L08_SIG2")
		(18 "In8.Cu" signal "L09_GND4")
		(2 "B.Cu" signal "BOTTOM")
		(9 "F.Adhes" user "F.Adhesive")
		(11 "B.Adhes" user "B.Adhesive")
		(13 "F.Paste" user "Package Geometry/Pastemask Top")
		(15 "B.Paste" user "Package Geometry/Pastemask Bottom")
		(5 "F.SilkS" user "Ref Des/Silkscreen Top")
		(7 "B.SilkS" user "Ref Des/Silkscreen Bottom")
		(1 "F.Mask" user "Board Geometry/Soldermask Top")
		(3 "B.Mask" user "Board Geometry/Soldermask Bottom")
		(17 "Dwgs.User" user "User.Drawings")
		(19 "Cmts.User" user "User.Comments")
		(21 "Eco1.User" user "User.Eco1")
		(23 "Eco2.User" user "User.Eco2")
		(25 "Edge.Cuts" user "Board Geometry/Outline")
		(27 "Margin" user)
		(31 "F.CrtYd" user "Package Geometry/Place Bound Top")
		(29 "B.CrtYd" user "Package Geometry/Place Bound Bottom")
		(35 "F.Fab" user "Ref Des/Assembly Top")
		(33 "B.Fab" user "Ref Des/Assembly Bottom")
	)
	(footprint ""
		(layer "F.Cu")
		(at 25.7556 -17.5514)
		(property "Reference" "U7"
			(at 0.94742 -2.52603 0)
			(unlocked yes)
			(layer "F.SilkS")
			(effects
				(font
					(size 0.7874 0.5842)
					(thickness 0.1524)
				)
			)
		)
		(property "Value" ""
			(at 0 0 0)
			(layer "F.Fab")
			(effects
				(font
					(size 1.27 1.27)
				)
			)
		)
		(property "Device Type" "AT24MAC402_SOT23_5-A221-00002-A"
			(at 0.0508 2.549906 0)
			(unlocked yes)
			(layer "F.Fab")
			(hide yes)
			(effects
				(font
					(size 0.7874 0.5842)
					(thickness 0.1524)
				)
			)
		)
		(property "User Part Number" "PARTNUM*"
			(at 0.0508 3.515106 0)
			(unlocked yes)
			(layer "Cmts.User")
			(hide yes)
			(effects
				(font
					(size 0.7874 0.5842)
					(thickness 0.1524)
				)
			)
		)
		(duplicate_pad_numbers_are_jumpers no)
		(fp_line
			(start -2.286 -1.45796)
			(end -1.0541 -1.45796)
			(stroke
				(width 0.1)
				(type default)
			)
			(layer "F.SilkS")
		)
		(fp_line
			(start -2.286 1.45796)
			(end -2.286 -1.45796)
			(stroke
				(width 0.1)
				(type default)
			)
			(layer "F.SilkS")
		)
		(fp_line
			(start -1.0541 -1.704086)
			(end 1.0541 -1.704086)
			(stroke
				(width 0.1)
				(type default)
			)
			(layer "F.SilkS")
		)
		(fp_line
			(start -1.0541 -1.45796)
			(end -1.0541 -1.704086)
			(stroke
				(width 0.1)
				(type default)
			)
			(layer "F.SilkS")
		)
		(fp_line
			(start -1.0541 1.45796)
			(end -2.286 1.45796)
			(stroke
				(width 0.1)
				(type default)
			)
			(layer "F.SilkS")
		)
		(fp_line
			(start -1.0541 1.704086)
			(end -1.0541 1.45796)
			(stroke
				(width 0.1)
				(type default)
			)
			(layer "F.SilkS")
		)
		(fp_line
			(start 1.0541 -1.704086)
			(end 1.0541 -1.45796)
			(stroke
				(width 0.1)
				(type default)
			)
			(layer "F.SilkS")
		)
		(fp_line
			(start 1.0541 -1.45796)
			(end 2.286 -1.45796)
			(stroke
				(width 0.1)
				(type default)
			)
			(layer "F.SilkS")
		)
		(fp_line
			(start 1.0541 -0.44196)
			(end 1.0541 0.44196)
			(stroke
				(width 0.1)
				(type default)
			)
			(layer "F.SilkS")
		)
		(fp_line
			(start 1.0541 0.44196)
			(end 2.286 0.44196)
			(stroke
				(width 0.1)
				(type default)
			)
			(layer "F.SilkS")
		)
		(fp_line
			(start 1.0541 1.45796)
			(end 1.0541 1.704086)
			(stroke
				(width 0.1)
				(type default)
			)
			(layer "F.SilkS")
		)
		(fp_line
			(start 1.0541 1.704086)
			(end -1.0541 1.704086)
			(stroke
				(width 0.1)
				(type default)
			)
			(layer "F.SilkS")
		)
		(fp_line
			(start 2.286 -1.45796)
			(end 2.286 -0.44196)
			(stroke
				(width 0.1)
				(type default)
			)
			(layer "F.SilkS")
		)
		(fp_line
			(start 2.286 -0.44196)
			(end 1.0541 -0.44196)
			(stroke
				(width 0.1)
				(type default)
			)
			(layer "F.SilkS")
		)
		(fp_line
			(start 2.286 0.44196)
			(end 2.286 1.45796)
			(stroke
				(width 0.1)
				(type default)
			)
			(layer "F.SilkS")
		)
		(fp_line
			(start 2.286 1.45796)
			(end 1.0541 1.45796)
			(stroke
				(width 0.1)
				(type default)
			)
			(layer "F.SilkS")
		)
		(fp_poly
			(pts
				(arc
					(start -1.59258 -1.9304)
					(mid -2.35458 -1.9304)
					(end -1.59258 -1.9304)
				)
			)
			(stroke
				(width 0)
				(type default)
			)
			(fill yes)
			(layer "F.SilkS")
		)
		(fp_rect
			(start -2.54 1.9558)
			(end 2.54 -1.9558)
			(stroke
				(width 0)
				(type default)
			)
			(fill no)
			(layer "F.CrtYd")
		)
		(fp_line
			(start -1.500124 -1.199896)
			(end -0.700024 -1.199896)
			(stroke
				(width 0.1)
				(type default)
			)
			(layer "F.Fab")
		)
		(fp_line
			(start -1.500124 -0.700024)
			(end -1.500124 -1.199896)
			(stroke
				(width 0.1)
				(type default)
			)
			(layer "F.Fab")
		)
		(fp_line
			(start -1.500124 -0.249936)
			(end -0.700024 -0.249936)
			(stroke
				(width 0.1)
				(type default)
			)
			(layer "F.Fab")
		)
		(fp_line
			(start -1.500124 0.249936)
			(end -1.500124 -0.249936)
			(stroke
				(width 0.1)
				(type default)
			)
			(layer "F.Fab")
		)
		(fp_line
			(start -1.500124 0.700024)
			(end -0.700024 0.700024)
			(stroke
				(width 0.1)
				(type default)
			)
			(layer "F.Fab")
		)
		(fp_line
			(start -1.500124 1.199896)
			(end -1.500124 0.700024)
			(stroke
				(width 0.1)
				(type default)
			)
			(layer "F.Fab")
		)
		(fp_line
			(start -0.8001 -1.450086)
			(end 0.8001 -1.450086)
			(stroke
				(width 0.1)
				(type default)
			)
			(layer "F.Fab")
		)
		(fp_line
			(start -0.8001 -1.199896)
			(end -0.8001 -1.450086)
			(stroke
				(width 0.1)
				(type default)
			)
			(layer "F.Fab")
		)
		(fp_line
			(start -0.8001 -0.700024)
			(end -0.8001 -0.249936)
			(stroke
				(width 0.1)
				(type default)
			)
			(layer "F.Fab")
		)
		(fp_line
			(start -0.8001 0.249936)
			(end -0.8001 0.700024)
			(stroke
				(width 0.1)
				(type default)
			)
			(layer "F.Fab")
		)
		(fp_line
			(start -0.8001 1.199896)
			(end -0.8001 1.450086)
			(stroke
				(width 0.1)
				(type default)
			)
			(layer "F.Fab")
		)
		(fp_line
			(start -0.8001 1.450086)
			(end -0.599948 1.249934)
			(stroke
				(width 0.1)
				(type default)
			)
			(layer "F.Fab")
		)
		(fp_line
			(start -0.8001 1.450086)
			(end 0.8001 1.450086)
			(stroke
				(width 0.1)
				(type default)
			)
			(layer "F.Fab")
		)
		(fp_line
			(start -0.700024 -1.199896)
			(end -0.700024 -0.700024)
			(stroke
				(width 0.1)
				(type default)
			)
			(layer "F.Fab")
		)
		(fp_line
			(start -0.700024 -0.700024)
			(end -1.500124 -0.700024)
			(stroke
				(width 0.1)
				(type default)
			)
			(layer "F.Fab")
		)
		(fp_line
			(start -0.700024 -0.249936)
			(end -0.700024 0.249936)
			(stroke
				(width 0.1)
				(type default)
			)
			(layer "F.Fab")
		)
		(fp_line
			(start -0.700024 0.249936)
			(end -1.500124 0.249936)
			(stroke
				(width 0.1)
				(type default)
			)
			(layer "F.Fab")
		)
		(fp_line
			(start -0.700024 0.700024)
			(end -0.700024 1.199896)
			(stroke
				(width 0.1)
				(type default)
			)
			(layer "F.Fab")
		)
		(fp_line
			(start -0.700024 1.199896)
			(end -1.500124 1.199896)
			(stroke
				(width 0.1)
				(type default)
			)
			(layer "F.Fab")
		)
		(fp_line
			(start -0.599948 -1.249934)
			(end -0.8001 -1.450086)
			(stroke
				(width 0.1)
				(type default)
			)
			(layer "F.Fab")
		)
		(fp_line
			(start -0.599948 -1.249934)
			(end 0.599948 -1.249934)
			(stroke
				(width 0.1)
				(type default)
			)
			(layer "F.Fab")
		)
		(fp_line
			(start -0.599948 1.249934)
			(end -0.599948 -1.249934)
			(stroke
				(width 0.1)
				(type default)
			)
			(layer "F.Fab")
		)
		(fp_line
			(start 0.599948 -1.249934)
			(end 0.599948 1.249934)
			(stroke
				(width 0.1)
				(type default)
			)
			(layer "F.Fab")
		)
		(fp_line
			(start 0.599948 -1.249934)
			(end 0.8001 -1.450086)
			(stroke
				(width 0.1)
				(type default)
			)
			(layer "F.Fab")
		)
		(fp_line
			(start 0.599948 1.249934)
			(end -0.599948 1.249934)
			(stroke
				(width 0.1)
				(type default)
			)
			(layer "F.Fab")
		)
		(fp_line
			(start 0.700024 -1.199896)
			(end 1.500124 -1.199896)
			(stroke
				(width 0.1)
				(type default)
			)
			(layer "F.Fab")
		)
		(fp_line
			(start 0.700024 -0.700024)
			(end 0.700024 -1.199896)
			(stroke
				(width 0.1)
				(type default)
			)
			(layer "F.Fab")
		)
		(fp_line
			(start 0.700024 0.700024)
			(end 1.500124 0.700024)
			(stroke
				(width 0.1)
				(type default)
			)
			(layer "F.Fab")
		)
		(fp_line
			(start 0.700024 1.199896)
			(end 0.700024 0.700024)
			(stroke
				(width 0.1)
				(type default)
			)
			(layer "F.Fab")
		)
		(fp_line
			(start 0.8001 -1.450086)
			(end 0.8001 -1.199896)
			(stroke
				(width 0.1)
				(type default)
			)
			(layer "F.Fab")
		)
		(fp_line
			(start 0.8001 -0.700024)
			(end 0.8001 0.700024)
			(stroke
				(width 0.1)
				(type default)
			)
			(layer "F.Fab")
		)
		(fp_line
			(start 0.8001 1.450086)
			(end 0.599948 1.249934)
			(stroke
				(width 0.1)
				(type default)
			)
			(layer "F.Fab")
		)
		(fp_line
			(start 0.8001 1.450086)
			(end 0.8001 1.199896)
			(stroke
				(width 0.1)
				(type default)
			)
			(layer "F.Fab")
		)
		(fp_line
			(start 1.500124 -1.199896)
			(end 1.500124 -0.700024)
			(stroke
				(width 0.1)
				(type default)
			)
			(layer "F.Fab")
		)
		(fp_line
			(start 1.500124 -0.700024)
			(end 0.700024 -0.700024)
			(stroke
				(width 0.1)
				(type default)
			)
			(layer "F.Fab")
		)
		(fp_line
			(start 1.500124 0.700024)
			(end 1.500124 1.199896)
			(stroke
				(width 0.1)
				(type default)
			)
			(layer "F.Fab")
		)
		(fp_line
			(start 1.500124 1.199896)
			(end 0.700024 1.199896)
			(stroke
				(width 0.1)
				(type default)
			)
			(layer "F.Fab")
		)
		(fp_poly
			(pts
				(arc
					(start -0.200152 -0.94996)
					(mid -0.499872 -0.94996)
					(end -0.200152 -0.94996)
				)
			)
			(stroke
				(width 0)
				(type default)
			)
			(fill yes)
			(layer "F.Fab")
		)
		(fp_text user "3"
			(at -1.71958 2.17297 0)
			(unlocked yes)
			(layer "F.SilkS")
			(effects
				(font
					(size 0.7874 0.5842)
					(thickness 0.1524)
				)
			)
		)
		(fp_text user "5"
			(at 2.6924 -1.84023 0)
			(unlocked yes)
			(layer "F.SilkS")
			(effects
				(font
					(size 0.7874 0.5842)
					(thickness 0.1524)
				)
			)
		)
		(fp_text user "4"
			(at 2.9464 1.58877 0)
			(unlocked yes)
			(layer "F.SilkS")
			(effects
				(font
					(size 0.7874 0.5842)
					(thickness 0.1524)
				)
			)
		)
		(fp_text user "3"
			(at -2.794 0.91567 0)
			(unlocked yes)
			(layer "F.Fab")
			(effects
				(font
					(size 0.7874 0.5842)
					(thickness 0.1524)
				)
			)
		)
		(fp_text user "5"
			(at 2.032 -0.83693 0)
			(unlocked yes)
			(layer "F.Fab")
			(effects
				(font
					(size 0.7874 0.5842)
					(thickness 0.1524)
				)
			)
		)
		(fp_text user "4"
			(at 2.032 1.09347 0)
			(unlocked yes)
			(layer "F.Fab")
			(effects
				(font
					(size 0.7874 0.5842)
					(thickness 0.1524)
				)
			)
		)
		(pad "1" smd rect
			(at -1.4351 -0.94996 90)
			(size 0.508 1.1938)
			(layers "F.Cu" "F.Mask" "F.Paste")
			(net "EEPROM_SCL")
		)
		(pad "2" smd rect
			(at -1.4351 0 90)
			(size 0.508 1.1938)
			(layers "F.Cu" "F.Mask" "F.Paste")
			(net "SG")
		)
		(pad "3" smd rect
			(at -1.4351 0.94996 90)
			(size 0.508 1.1938)
			(layers "F.Cu" "F.Mask" "F.Paste")
			(net "PRI_EEPROM_SDA")
		)
		(pad "4" smd rect
			(at 1.4351 0.94996 90)
			(size 0.508 1.1938)
			(layers "F.Cu" "F.Mask" "F.Paste")
			(net "XP3R3V_FPGA")
		)
		(pad "5" smd rect
			(at 1.4351 -0.94996 90)
			(size 0.508 1.1938)
			(layers "F.Cu" "F.Mask" "F.Paste")
			(net "SN_EEPROM_WP")
		)
	)
	(footprint ""
		(layer "F.Cu")
		(at 11.557 -30.4546 -90)
		(property "Reference" "R496"
			(at -0.1524 2.11963 90)
			(unlocked yes)
			(layer "F.SilkS")
			(effects
				(font
					(size 0.7874 0.5842)
					(thickness 0.1524)
				)
			)
		)
		(property "Value" "VAL*"
			(at 0.02032 2.13233 270)
			(unlocked yes)
			(layer "F.Fab")
			(hide yes)
			(effects
				(font
					(size 0.7874 0.5842)
					(thickness 0.1524)
				)
			)
		)
		(property "Tolerance" "TOL*"
			(at 0.044704 3.05435 270)
			(unlocked yes)
			(layer "Cmts.User")
			(hide yes)
			(effects
				(font
					(size 0.7874 0.5842)
					(thickness 0.1524)
				)
			)
		)
		(property "User Part Number" "PARTNUM*"
			(at 0.02032 4.024884 270)
			(unlocked yes)
			(layer "Cmts.User")
			(hide yes)
			(effects
				(font
					(size 0.7874 0.5842)
					(thickness 0.1524)
				)
			)
		)
		(property "Device Type" "RESISTOR-G155-11004-01,1MOHM,1%"
			(at 0.008382 1.210564 270)
			(unlocked yes)
			(layer "F.Fab")
			(hide yes)
			(effects
				(font
					(size 0.7874 0.5842)
					(thickness 0.1524)
				)
			)
		)
		(duplicate_pad_numbers_are_jumpers no)
		(fp_line
			(start -1.143 0.5588)
			(end 1.143 0.5588)
			(stroke
				(width 0.1)
				(type default)
			)
			(layer "F.SilkS")
		)
		(fp_line
			(start 1.143 0.5588)
			(end 1.143 -0.5588)
			(stroke
				(width 0.1)
				(type default)
			)
			(layer "F.SilkS")
		)
		(fp_line
			(start -1.143 -0.5588)
			(end -1.143 0.5588)
			(stroke
				(width 0.1)
				(type default)
			)
			(layer "F.SilkS")
		)
		(fp_line
			(start 1.143 -0.5588)
			(end -1.143 -0.5588)
			(stroke
				(width 0.1)
				(type default)
			)
			(layer "F.SilkS")
		)
		(fp_poly
			(pts
				(xy -1.143 0.5588) (xy 1.143 0.5588) (xy 1.143 -0.5588) (xy -1.143 -0.5588)
			)
			(stroke
				(width 0)
				(type default)
			)
			(fill no)
			(layer "F.CrtYd")
		)
		(fp_line
			(start -0.508 0.3048)
			(end 0.508 0.3048)
			(stroke
				(width 0.1)
				(type default)
			)
			(layer "F.Fab")
		)
		(fp_line
			(start 0.508 0.3048)
			(end 0.508 -0.3048)
			(stroke
				(width 0.1)
				(type default)
			)
			(layer "F.Fab")
		)
		(fp_line
			(start -0.508 -0.3048)
			(end -0.508 0.3048)
			(stroke
				(width 0.1)
				(type default)
			)
			(layer "F.Fab")
		)
		(fp_line
			(start 0.508 -0.3048)
			(end -0.508 -0.3048)
			(stroke
				(width 0.1)
				(type default)
			)
			(layer "F.Fab")
		)
		(pad "1" smd rect
			(at -0.5334 0 270)
			(size 0.7112 0.6096)
			(layers "F.Cu" "F.Mask" "F.Paste")
			(net "SG")
		)
		(pad "2" smd rect
			(at 0.5334 0 270)
			(size 0.7112 0.6096)
			(layers "F.Cu" "F.Mask" "F.Paste")
			(net "BF_SMA3_SIG_IO_CONN")
		)
		(zone
			(layer "F.Cu")
			(hatch none 0.5)
			(connect_pads
				(clearance 0)
			)
			(min_thickness 0.25)
			(keepout
				(tracks not_allowed)
				(vias allowed)
				(pads allowed)
				(copperpour not_allowed)
				(footprints allowed)
			)
			(placement
				(enabled no)
				(sheetname "")
			)
			(fill
				(thermal_gap 0.5)
				(thermal_bridge_width 0.5)
				(island_removal_mode 0)
			)
			(polygon
				(pts
					(xy 11.2522 -30.5308) (xy 11.2522 -30.3784) (xy 11.8618 -30.3784) (xy 11.8618 -30.5308)
				)
			)
		)
		(zone
			(layer "F.Cu")
			(hatch none 0.5)
			(connect_pads
				(clearance 0)
			)
			(min_thickness 0.25)
			(keepout
				(tracks allowed)
				(vias not_allowed)
				(pads allowed)
				(copperpour not_allowed)
				(footprints allowed)
			)
			(placement
				(enabled no)
				(sheetname "")
			)
			(fill
				(thermal_gap 0.5)
				(thermal_bridge_width 0.5)
				(island_removal_mode 0)
			)
			(polygon
				(pts
					(xy 11.2522 -30.5308) (xy 11.2522 -30.3784) (xy 11.8618 -30.3784) (xy 11.8618 -30.5308)
				)
			)
		)
	)
	(footprint ""
		(layer "F.Cu")
		(at 141.05001 -104.350058 -90)
		(property "Reference" "DS7"
			(at 0.972058 1.57226 90)
			(unlocked yes)
			(layer "F.SilkS")
			(effects
				(font
					(size 0.635 0.4064)
					(thickness 0.1524)
				)
			)
		)
		(property "Value" ""
			(at 0 0 270)
			(layer "F.Fab")
			(effects
				(font
					(size 1.27 1.27)
				)
			)
		)
		(property "Device Type" "OPTICAL-G170-10143-01"
			(at 0.1778 1.483081 270)
			(unlocked yes)
			(layer "F.Fab")
			(hide yes)
			(effects
				(font
					(size 0.786892 0.583946)
					(thickness 0.000001)
				)
			)
		)
		(property "User Part Number" "PARTNUM*"
			(at 0.1778 2.422881 270)
			(unlocked yes)
			(layer "Cmts.User")
			(hide yes)
			(effects
				(font
					(size 0.786892 0.583946)
					(thickness 0.000001)
				)
			)
		)
		(duplicate_pad_numbers_are_jumpers no)
		(fp_line
			(start -1.0668 1.2192)
			(end -2.3368 1.2192)
			(stroke
				(width 0.1)
				(type default)
			)
			(layer "F.SilkS")
		)
		(fp_line
			(start -1.397508 0.704088)
			(end -1.397508 -0.704088)
			(stroke
				(width 0.1)
				(type default)
			)
			(layer "F.SilkS")
		)
		(fp_line
			(start 1.397508 0.704088)
			(end -1.397508 0.704088)
			(stroke
				(width 0.1)
				(type default)
			)
			(layer "F.SilkS")
		)
		(fp_line
			(start -1.7018 0.5842)
			(end -1.7018 1.8542)
			(stroke
				(width 0.1)
				(type default)
			)
			(layer "F.SilkS")
		)
		(fp_line
			(start -1.397508 -0.704088)
			(end 1.397508 -0.704088)
			(stroke
				(width 0.1)
				(type default)
			)
			(layer "F.SilkS")
		)
		(fp_line
			(start 1.397508 -0.704088)
			(end 1.397508 0.704088)
			(stroke
				(width 0.1)
				(type default)
			)
			(layer "F.SilkS")
		)
		(fp_rect
			(start 1.397508 -0.704088)
			(end 1.905508 0.704088)
			(stroke
				(width 0)
				(type default)
			)
			(fill yes)
			(layer "F.SilkS")
		)
		(fp_rect
			(start -1.651508 -0.958088)
			(end 1.905508 0.958088)
			(stroke
				(width 0)
				(type default)
			)
			(fill no)
			(layer "F.CrtYd")
		)
		(fp_line
			(start -0.9398 1.4732)
			(end -2.2098 1.4732)
			(stroke
				(width 0.1)
				(type default)
			)
			(layer "F.Fab")
		)
		(fp_line
			(start -1.5748 0.8382)
			(end -1.5748 2.1082)
			(stroke
				(width 0.1)
				(type default)
			)
			(layer "F.Fab")
		)
		(fp_line
			(start -0.850138 0.450088)
			(end 0.850138 0.450088)
			(stroke
				(width 0.1)
				(type default)
			)
			(layer "F.Fab")
		)
		(fp_line
			(start 0.850138 0.450088)
			(end 0.850138 -0.450088)
			(stroke
				(width 0.1)
				(type default)
			)
			(layer "F.Fab")
		)
		(fp_line
			(start -0.850138 -0.450088)
			(end -0.850138 0.450088)
			(stroke
				(width 0.1)
				(type default)
			)
			(layer "F.Fab")
		)
		(fp_line
			(start 0.850138 -0.450088)
			(end -0.850138 -0.450088)
			(stroke
				(width 0.1)
				(type default)
			)
			(layer "F.Fab")
		)
		(fp_rect
			(start 0.342138 -0.450088)
			(end 0.850138 0.450088)
			(stroke
				(width 0)
				(type default)
			)
			(fill yes)
			(layer "F.Fab")
		)
		(fp_text user "A"
			(at -0.647192 1.47701 0)
			(unlocked yes)
			(layer "F.SilkS")
			(effects
				(font
					(size 0.635 0.4064)
					(thickness 0.1524)
				)
			)
		)
		(fp_text user "C"
			(at 2.400808 0.71501 0)
			(unlocked yes)
			(layer "F.SilkS")
			(effects
				(font
					(size 0.635 0.4064)
					(thickness 0.1524)
				)
			)
		)
		(fp_text user "A"
			(at -0.766572 0.96901 0)
			(unlocked yes)
			(layer "F.Fab")
			(effects
				(font
					(size 0.7874 0.5842)
					(thickness 0.1524)
				)
			)
		)
		(fp_text user "C"
			(at 1.646428 0.96901 0)
			(unlocked yes)
			(layer "F.Fab")
			(effects
				(font
					(size 0.7874 0.5842)
					(thickness 0.1524)
				)
			)
		)
		(pad "A" smd rect
			(at -0.749808 0 270)
			(size 0.7874 0.7874)
			(layers "F.Cu" "F.Mask" "F.Paste")
			(net "UNNAMED_14_OPTICAL_I141_A")
		)
		(pad "C" smd rect
			(at 0.749808 0 270)
			(size 0.7874 0.7874)
			(layers "F.Cu" "F.Mask" "F.Paste")
			(net "SG")
		)
	)
)
